(kicad_pcb
	(version 20260206)
	(generator "pcbnew")
	(generator_version "10.0")
	(general
		(thickness 1.6)
		(legacy_teardrops no)
	)
	(paper "A4")
	(title_block
		(title "v1-chassis-manager — T6M_CM_d_v01_1031_1645.brd")
		(comment 1 "Open CloudServer (Microsoft) / footprints 1720-1727 of 2512")
	)
	(layers
		(0 "F.Cu" signal "TOP")
		(4 "In1.Cu" signal "GND1")
		(6 "In2.Cu" signal "IN1")
		(8 "In3.Cu" signal "VCC1")
		(10 "In4.Cu" signal "VCC2")
		(12 "In5.Cu" signal "GND2")
		(14 "In6.Cu" signal "IN2")
		(16 "In7.Cu" signal "IN3")
		(18 "In8.Cu" signal "GND3")
		(2 "B.Cu" signal "BOTTOM")
		(9 "F.Adhes" user "F.Adhesive")
		(11 "B.Adhes" user "B.Adhesive")
		(13 "F.Paste" user "Package Geometry/Pastemask Top")
		(15 "B.Paste" user "Package Geometry/Pastemask Bottom")
		(5 "F.SilkS" user "Ref Des/Silkscreen Top")
		(7 "B.SilkS" user "Ref Des/Silkscreen Bottom")
		(1 "F.Mask" user "Board Geometry/Soldermask Top")
		(3 "B.Mask" user "Board Geometry/Soldermask Bottom")
		(17 "Dwgs.User" user "User.Drawings")
		(19 "Cmts.User" user "User.Comments")
		(21 "Eco1.User" user "User.Eco1")
		(23 "Eco2.User" user "User.Eco2")
		(25 "Edge.Cuts" user "Board Geometry/Outline")
		(27 "Margin" user)
		(31 "F.CrtYd" user "Package Geometry/Place Bound Top")
		(29 "B.CrtYd" user "Package Geometry/Place Bound Bottom")
		(35 "F.Fab" user "Ref Des/Assembly Top")
		(33 "B.Fab" user "Ref Des/Assembly Bottom")
	)
	(footprint ""
		(layer "B.Cu")
		(at 38.280086 -129.121662 -90)
		(property "Reference" "C230"
			(at 1.251458 1.138428 270)
			(unlocked yes)
			(layer "B.SilkS")
			(effects
				(font
					(size 0.7874 0.5842)
					(thickness 0.1524)
				)
				(justify left mirror)
			)
		)
		(property "Value" ""
			(at 0 0 90)
			(layer "B.Fab")
			(effects
				(font
					(size 1.27 1.27)
				)
				(justify mirror)
			)
		)
		(duplicate_pad_numbers_are_jumpers no)
		(fp_line
			(start -0.7874 0.4064)
			(end 0.7874 0.4064)
			(stroke
				(width 0.1524)
				(type default)
			)
			(layer "B.SilkS")
		)
		(fp_line
			(start 0.7874 0.4064)
			(end 0.7874 -0.4064)
			(stroke
				(width 0.1524)
				(type default)
			)
			(layer "B.SilkS")
		)
		(fp_line
			(start 0 0.381)
			(end 0 -0.381)
			(stroke
				(width 0.1524)
				(type default)
			)
			(layer "B.SilkS")
		)
		(fp_line
			(start -0.7874 -0.4064)
			(end -0.7874 0.4064)
			(stroke
				(width 0.1524)
				(type default)
			)
			(layer "B.SilkS")
		)
		(fp_line
			(start 0.7874 -0.4064)
			(end -0.7874 -0.4064)
			(stroke
				(width 0.1524)
				(type default)
			)
			(layer "B.SilkS")
		)
		(fp_poly
			(pts
				(xy 0.5334 0.254) (xy 0.635 0.254) (xy 0.635 0.2286) (xy 0.635 -0.254) (xy 0.5334 -0.254) (xy 0.5334 -0.2794)
				(xy -0.5334 -0.2794) (xy -0.5334 -0.254) (xy -0.635 -0.254) (xy -0.635 0.254) (xy -0.5334 0.254)
				(xy -0.5334 0.2794) (xy 0.508 0.2794) (xy 0.5334 0.2794)
			)
			(stroke
				(width 0)
				(type default)
			)
			(fill no)
			(layer "B.CrtYd")
		)
		(pad "1" smd rect
			(at -0.40005 0 90)
			(size 0.4572 0.508)
			(layers "B.Cu" "B.Mask" "B.Paste")
			(net "P1V538_BMC_NODE1")
		)
		(pad "2" smd rect
			(at 0.40005 0 90)
			(size 0.4572 0.508)
			(layers "B.Cu" "B.Mask" "B.Paste")
			(net "GND")
		)
	)
	(footprint ""
		(layer "B.Cu")
		(at 162.296602 -175.827436 -90)
		(property "Reference" "U59"
			(at 5.79755 0.536956 0)
			(unlocked yes)
			(layer "B.SilkS")
			(effects
				(font
					(size 0.7874 0.5842)
					(thickness 0.1524)
				)
				(justify left mirror)
			)
		)
		(property "Value" ""
			(at 0 0 90)
			(layer "B.Fab")
			(effects
				(font
					(size 1.27 1.27)
				)
				(justify mirror)
			)
		)
		(duplicate_pad_numbers_are_jumpers no)
		(fp_line
			(start -4.9022 2.0066)
			(end 4.9022 2.0066)
			(stroke
				(width 0.1524)
				(type default)
			)
			(layer "B.SilkS")
		)
		(fp_line
			(start 4.9022 2.0066)
			(end 4.9022 0.5842)
			(stroke
				(width 0.1524)
				(type default)
			)
			(layer "B.SilkS")
		)
		(fp_line
			(start 4.9022 0.5842)
			(end 4.318 0)
			(stroke
				(width 0.1524)
				(type default)
			)
			(layer "B.SilkS")
		)
		(fp_line
			(start 4.318 0)
			(end 4.9022 -0.5842)
			(stroke
				(width 0.1524)
				(type default)
			)
			(layer "B.SilkS")
		)
		(fp_line
			(start 4.9022 -0.5842)
			(end 4.9022 -2.0066)
			(stroke
				(width 0.1524)
				(type default)
			)
			(layer "B.SilkS")
		)
		(fp_line
			(start -4.9022 -2.0066)
			(end -4.9022 2.0066)
			(stroke
				(width 0.1524)
				(type default)
			)
			(layer "B.SilkS")
		)
		(fp_line
			(start 4.9022 -2.0066)
			(end -4.9022 -2.0066)
			(stroke
				(width 0.1524)
				(type default)
			)
			(layer "B.SilkS")
		)
		(fp_circle
			(center 4.318 1.524)
			(end 4.318 1.27)
			(stroke
				(width 0.1524)
				(type default)
			)
			(fill no)
			(layer "B.SilkS")
		)
		(fp_rect
			(start 4.9022 3.6703)
			(end -4.9022 -3.6703)
			(stroke
				(width 0)
				(type default)
			)
			(fill no)
			(layer "B.CrtYd")
		)
		(pad "1" smd rect
			(at 4.225036 2.921 90)
			(size 0.3556 1.4986)
			(layers "B.Cu" "B.Mask" "B.Paste")
			(net "N54365827")
		)
		(pad "2" smd rect
			(at 3.57505 2.921 90)
			(size 0.3556 1.4986)
			(layers "B.Cu" "B.Mask" "B.Paste")
			(net "N54365829")
		)
		(pad "3" smd rect
			(at 2.925064 2.921 90)
			(size 0.3556 1.4986)
			(layers "B.Cu" "B.Mask" "B.Paste")
			(net "N54365837")
		)
		(pad "4" smd rect
			(at 2.275078 2.921 90)
			(size 0.3556 1.4986)
			(layers "B.Cu" "B.Mask" "B.Paste")
			(net "UART_RX_RP6_L")
		)
		(pad "5" smd rect
			(at 1.625092 2.921 90)
			(size 0.3556 1.4986)
			(layers "B.Cu" "B.Mask" "B.Paste")
			(net "UART_RI_RP6_L_N")
		)
		(pad "6" smd rect
			(at 0.975106 2.921 90)
			(size 0.3556 1.4986)
			(layers "B.Cu" "B.Mask" "B.Paste")
			(net "N54365764")
		)
		(pad "7" smd rect
			(at 0.32512 2.921 90)
			(size 0.3556 1.4986)
			(layers "B.Cu" "B.Mask" "B.Paste")
			(net "N54365764")
		)
		(pad "8" smd rect
			(at -0.32512 2.921 90)
			(size 0.3556 1.4986)
			(layers "B.Cu" "B.Mask" "B.Paste")
			(net "N54365764")
		)
		(pad "9" smd rect
			(at -0.975106 2.921 90)
			(size 0.3556 1.4986)
			(layers "B.Cu" "B.Mask" "B.Paste")
			(net "UART_RTS_RP6_L_N")
		)
		(pad "10" smd rect
			(at -1.625092 2.921 90)
			(size 0.3556 1.4986)
			(layers "B.Cu" "B.Mask" "B.Paste")
			(net "UART_TX_RP6_L")
		)
		(pad "11" smd rect
			(at -2.275078 2.921 90)
			(size 0.3556 1.4986)
			(layers "B.Cu" "B.Mask" "B.Paste")
			(net "UART_DTR_RP6_L_N")
		)
		(pad "12" smd rect
			(at -2.925064 2.921 90)
			(size 0.3556 1.4986)
			(layers "B.Cu" "B.Mask" "B.Paste")
			(net "CPLD_UART_DTR_P4_R_N")
		)
		(pad "13" smd rect
			(at -3.57505 2.921 90)
			(size 0.3556 1.4986)
			(layers "B.Cu" "B.Mask" "B.Paste")
			(net "CPLD_UART_TX_P4")
		)
		(pad "14" smd rect
			(at -4.225036 2.921 90)
			(size 0.3556 1.4986)
			(layers "B.Cu" "B.Mask" "B.Paste")
			(net "CPLD_UART_RTS_P4_R_N")
		)
		(pad "15" smd rect
			(at -4.225036 -2.921 90)
			(size 0.3556 1.4986)
			(layers "B.Cu" "B.Mask" "B.Paste")
			(net "Net_2293")
		)
		(pad "16" smd rect
			(at -3.57505 -2.921 90)
			(size 0.3556 1.4986)
			(layers "B.Cu" "B.Mask" "B.Paste")
			(net "Net_2294")
		)
		(pad "17" smd rect
			(at -2.925064 -2.921 90)
			(size 0.3556 1.4986)
			(layers "B.Cu" "B.Mask" "B.Paste")
			(net "Net_2295")
		)
		(pad "18" smd rect
			(at -2.275078 -2.921 90)
			(size 0.3556 1.4986)
			(layers "B.Cu" "B.Mask" "B.Paste")
			(net "CPLD_UART_RI_P4_LS_N")
		)
		(pad "19" smd rect
			(at -1.625092 -2.921 90)
			(size 0.3556 1.4986)
			(layers "B.Cu" "B.Mask" "B.Paste")
			(net "CPLD_UART_RX_P4_R")
		)
		(pad "20" smd rect
			(at -0.975106 -2.921 90)
			(size 0.3556 1.4986)
			(layers "B.Cu" "B.Mask" "B.Paste")
			(net "Net_2296")
		)
		(pad "21" smd rect
			(at -0.32512 -2.921 90)
			(size 0.3556 1.4986)
			(layers "B.Cu" "B.Mask" "B.Paste")
			(net "Net_2297")
		)
		(pad "22" smd rect
			(at 0.32512 -2.921 90)
			(size 0.3556 1.4986)
			(layers "B.Cu" "B.Mask" "B.Paste")
			(net "N54365776")
		)
		(pad "23" smd rect
			(at 0.975106 -2.921 90)
			(size 0.3556 1.4986)
			(layers "B.Cu" "B.Mask" "B.Paste")
			(net "N54365772")
		)
		(pad "24" smd rect
			(at 1.625092 -2.921 90)
			(size 0.3556 1.4986)
			(layers "B.Cu" "B.Mask" "B.Paste")
			(net "N54365823")
		)
		(pad "25" smd rect
			(at 2.275078 -2.921 90)
			(size 0.3556 1.4986)
			(layers "B.Cu" "B.Mask" "B.Paste")
			(net "GND")
		)
		(pad "26" smd rect
			(at 2.925064 -2.921 90)
			(size 0.3556 1.4986)
			(layers "B.Cu" "B.Mask" "B.Paste")
			(net "P3V3_NODE1")
		)
		(pad "27" smd rect
			(at 3.57505 -2.921 90)
			(size 0.3556 1.4986)
			(layers "B.Cu" "B.Mask" "B.Paste")
			(net "N54365835")
		)
		(pad "28" smd rect
			(at 4.225036 -2.921 90)
			(size 0.3556 1.4986)
			(layers "B.Cu" "B.Mask" "B.Paste")
			(net "N54365821")
		)
	)
	(footprint ""
		(layer "B.Cu")
		(at 68.314062 -29.394658 -90)
		(property "Reference" "R203"
			(at -1.23444 0.149352 270)
			(unlocked yes)
			(layer "B.SilkS")
			(effects
				(font
					(size 0.7874 0.5842)
					(thickness 0.1524)
				)
				(justify left mirror)
			)
		)
		(property "Value" ""
			(at 0 0 90)
			(layer "B.Fab")
			(effects
				(font
					(size 1.27 1.27)
				)
				(justify mirror)
			)
		)
		(duplicate_pad_numbers_are_jumpers no)
		(fp_line
			(start -0.7874 0.4064)
			(end 0.7874 0.4064)
			(stroke
				(width 0.1524)
				(type default)
			)
			(layer "B.SilkS")
		)
		(fp_line
			(start 0.7874 0.4064)
			(end 0.7874 -0.4064)
			(stroke
				(width 0.1524)
				(type default)
			)
			(layer "B.SilkS")
		)
		(fp_line
			(start -0.7874 -0.4064)
			(end -0.7874 0.4064)
			(stroke
				(width 0.1524)
				(type default)
			)
			(layer "B.SilkS")
		)
		(fp_line
			(start 0.7874 -0.4064)
			(end -0.7874 -0.4064)
			(stroke
				(width 0.1524)
				(type default)
			)
			(layer "B.SilkS")
		)
		(fp_poly
			(pts
				(xy 0.508 0.2794) (xy 0.508 0.2286) (xy 0.635 0.2286) (xy 0.635 -0.254) (xy 0.5334 -0.254) (xy 0.5334 -0.2794)
				(xy -0.5334 -0.2794) (xy -0.5334 -0.254) (xy -0.635 -0.254) (xy -0.635 0.254) (xy -0.5334 0.254)
				(xy -0.5334 0.2794)
			)
			(stroke
				(width 0)
				(type default)
			)
			(fill no)
			(layer "B.CrtYd")
		)
		(pad "1" smd rect
			(at -0.40005 0 90)
			(size 0.4572 0.508)
			(layers "B.Cu" "B.Mask" "B.Paste")
			(net "P1V5_NODE1_DDR3_VREF_A_A")
		)
		(pad "2" smd rect
			(at 0.40005 0 90)
			(size 0.4572 0.508)
			(layers "B.Cu" "B.Mask" "B.Paste")
			(net "GND")
		)
	)
	(footprint ""
		(layer "B.Cu")
		(at 47.10176 -185.205624 -90)
		(property "Reference" "R847"
			(at -4.15163 -0.163068 270)
			(unlocked yes)
			(layer "B.SilkS")
			(effects
				(font
					(size 0.7874 0.5842)
					(thickness 0.1524)
				)
				(justify left mirror)
			)
		)
		(property "Value" ""
			(at 0 0 90)
			(layer "B.Fab")
			(effects
				(font
					(size 1.27 1.27)
				)
				(justify mirror)
			)
		)
		(duplicate_pad_numbers_are_jumpers no)
		(fp_line
			(start -0.7874 0.4064)
			(end 0.7874 0.4064)
			(stroke
				(width 0.1524)
				(type default)
			)
			(layer "B.SilkS")
		)
		(fp_line
			(start 0.7874 0.4064)
			(end 0.7874 -0.4064)
			(stroke
				(width 0.1524)
				(type default)
			)
			(layer "B.SilkS")
		)
		(fp_line
			(start -0.7874 -0.4064)
			(end -0.7874 0.4064)
			(stroke
				(width 0.1524)
				(type default)
			)
			(layer "B.SilkS")
		)
		(fp_line
			(start 0.7874 -0.4064)
			(end -0.7874 -0.4064)
			(stroke
				(width 0.1524)
				(type default)
			)
			(layer "B.SilkS")
		)
		(fp_poly
			(pts
				(xy 0.508 0.2794) (xy 0.508 0.2286) (xy 0.635 0.2286) (xy 0.635 -0.254) (xy 0.5334 -0.254) (xy 0.5334 -0.2794)
				(xy -0.5334 -0.2794) (xy -0.5334 -0.254) (xy -0.635 -0.254) (xy -0.635 0.254) (xy -0.5334 0.254)
				(xy -0.5334 0.2794)
			)
			(stroke
				(width 0)
				(type default)
			)
			(fill no)
			(layer "B.CrtYd")
		)
		(pad "1" smd rect
			(at -0.40005 0 90)
			(size 0.4572 0.508)
			(layers "B.Cu" "B.Mask" "B.Paste")
			(net "PSU6_DC_OK_R")
		)
		(pad "2" smd rect
			(at 0.40005 0 90)
			(size 0.4572 0.508)
			(layers "B.Cu" "B.Mask" "B.Paste")
			(net "PSU6_DC_OK_R_BUF")
		)
	)
	(footprint ""
		(layer "B.Cu")
		(at 35.86988 -64.748156 180)
		(property "Reference" "C19"
			(at 2.232406 0.057658 0)
			(unlocked yes)
			(layer "B.SilkS")
			(effects
				(font
					(size 0.7874 0.5842)
					(thickness 0.1524)
				)
				(justify left mirror)
			)
		)
		(property "Value" ""
			(at 0 0 0)
			(layer "B.Fab")
			(effects
				(font
					(size 1.27 1.27)
				)
				(justify mirror)
			)
		)
		(duplicate_pad_numbers_are_jumpers no)
		(fp_line
			(start 0.7874 0.4064)
			(end 0.7874 -0.4064)
			(stroke
				(width 0.1524)
				(type default)
			)
			(layer "B.SilkS")
		)
		(fp_line
			(start 0.7874 -0.4064)
			(end -0.7874 -0.4064)
			(stroke
				(width 0.1524)
				(type default)
			)
			(layer "B.SilkS")
		)
		(fp_line
			(start 0 0.381)
			(end 0 -0.381)
			(stroke
				(width 0.1524)
				(type default)
			)
			(layer "B.SilkS")
		)
		(fp_line
			(start -0.7874 0.4064)
			(end 0.7874 0.4064)
			(stroke
				(width 0.1524)
				(type default)
			)
			(layer "B.SilkS")
		)
		(fp_line
			(start -0.7874 -0.4064)
			(end -0.7874 0.4064)
			(stroke
				(width 0.1524)
				(type default)
			)
			(layer "B.SilkS")
		)
		(fp_poly
			(pts
				(xy 0.5334 0.254) (xy 0.635 0.254) (xy 0.635 0.2286) (xy 0.635 -0.254) (xy 0.5334 -0.254) (xy 0.5334 -0.2794)
				(xy -0.5334 -0.2794) (xy -0.5334 -0.254) (xy -0.635 -0.254) (xy -0.635 0.254) (xy -0.5334 0.254)
				(xy -0.5334 0.2794) (xy 0.508 0.2794) (xy 0.5334 0.2794)
			)
			(stroke
				(width 0)
				(type default)
			)
			(fill no)
			(layer "B.CrtYd")
		)
		(pad "1" smd rect
			(at -0.40005 0)
			(size 0.4572 0.508)
			(layers "B.Cu" "B.Mask" "B.Paste")
			(net "P2E_CPU_NIC1_NODE1_TX_C_DP")
		)
		(pad "2" smd rect
			(at 0.40005 0)
			(size 0.4572 0.508)
			(layers "B.Cu" "B.Mask" "B.Paste")
			(net "P2E_CPU_NIC1_NODE1_TX_DP")
		)
	)
	(footprint ""
		(layer "B.Cu")
		(at 61.96076 -188.126624 90)
		(property "Reference" "R913"
			(at 4.276598 -0.10922 270)
			(unlocked yes)
			(layer "B.SilkS")
			(effects
				(font
					(size 0.7874 0.5842)
					(thickness 0.1524)
				)
				(justify left mirror)
			)
		)
		(property "Value" ""
			(at 0 0 90)
			(layer "B.Fab")
			(effects
				(font
					(size 1.27 1.27)
				)
				(justify mirror)
			)
		)
		(duplicate_pad_numbers_are_jumpers no)
		(fp_line
			(start 0.7874 -0.4064)
			(end -0.7874 -0.4064)
			(stroke
				(width 0.1524)
				(type default)
			)
			(layer "B.SilkS")
		)
		(fp_line
			(start -0.7874 -0.4064)
			(end -0.7874 0.4064)
			(stroke
				(width 0.1524)
				(type default)
			)
			(layer "B.SilkS")
		)
		(fp_line
			(start 0.7874 0.4064)
			(end 0.7874 -0.4064)
			(stroke
				(width 0.1524)
				(type default)
			)
			(layer "B.SilkS")
		)
		(fp_line
			(start -0.7874 0.4064)
			(end 0.7874 0.4064)
			(stroke
				(width 0.1524)
				(type default)
			)
			(layer "B.SilkS")
		)
		(fp_poly
			(pts
				(xy 0.508 0.2794) (xy 0.508 0.2286) (xy 0.635 0.2286) (xy 0.635 -0.254) (xy 0.5334 -0.254) (xy 0.5334 -0.2794)
				(xy -0.5334 -0.2794) (xy -0.5334 -0.254) (xy -0.635 -0.254) (xy -0.635 0.254) (xy -0.5334 0.254)
				(xy -0.5334 0.2794)
			)
			(stroke
				(width 0)
				(type default)
			)
			(fill no)
			(layer "B.CrtYd")
		)
		(pad "1" smd rect
			(at -0.40005 0 270)
			(size 0.4572 0.508)
			(layers "B.Cu" "B.Mask" "B.Paste")
			(net "UART_T1_NODE2_RXD")
		)
		(pad "2" smd rect
			(at 0.40005 0 270)
			(size 0.4572 0.508)
			(layers "B.Cu" "B.Mask" "B.Paste")
			(net "UART_T1_NODE2_RXD_R")
		)
	)
	(footprint ""
		(layer "B.Cu")
		(at 106.28376 -188.126624 -90)
		(property "Reference" "C659"
			(at -4.10337 0.150368 270)
			(unlocked yes)
			(layer "B.SilkS")
			(effects
				(font
					(size 0.7874 0.5842)
					(thickness 0.1524)
				)
				(justify left mirror)
			)
		)
		(property "Value" ""
			(at 0 0 90)
			(layer "B.Fab")
			(effects
				(font
					(size 1.27 1.27)
				)
				(justify mirror)
			)
		)
		(duplicate_pad_numbers_are_jumpers no)
		(fp_line
			(start -0.7874 0.4064)
			(end 0.7874 0.4064)
			(stroke
				(width 0.1524)
				(type default)
			)
			(layer "B.SilkS")
		)
		(fp_line
			(start 0.7874 0.4064)
			(end 0.7874 -0.4064)
			(stroke
				(width 0.1524)
				(type default)
			)
			(layer "B.SilkS")
		)
		(fp_line
			(start 0 0.381)
			(end 0 -0.381)
			(stroke
				(width 0.1524)
				(type default)
			)
			(layer "B.SilkS")
		)
		(fp_line
			(start -0.7874 -0.4064)
			(end -0.7874 0.4064)
			(stroke
				(width 0.1524)
				(type default)
			)
			(layer "B.SilkS")
		)
		(fp_line
			(start 0.7874 -0.4064)
			(end -0.7874 -0.4064)
			(stroke
				(width 0.1524)
				(type default)
			)
			(layer "B.SilkS")
		)
		(fp_poly
			(pts
				(xy 0.5334 0.254) (xy 0.635 0.254) (xy 0.635 0.2286) (xy 0.635 -0.254) (xy 0.5334 -0.254) (xy 0.5334 -0.2794)
				(xy -0.5334 -0.2794) (xy -0.5334 -0.254) (xy -0.635 -0.254) (xy -0.635 0.254) (xy -0.5334 0.254)
				(xy -0.5334 0.2794) (xy 0.508 0.2794) (xy 0.5334 0.2794)
			)
			(stroke
				(width 0)
				(type default)
			)
			(fill no)
			(layer "B.CrtYd")
		)
		(pad "1" smd rect
			(at -0.40005 0 90)
			(size 0.4572 0.508)
			(layers "B.Cu" "B.Mask" "B.Paste")
			(net "T5_NODE1_EN_R")
		)
		(pad "2" smd rect
			(at 0.40005 0 90)
			(size 0.4572 0.508)
			(layers "B.Cu" "B.Mask" "B.Paste")
			(net "GND")
		)
	)
	(footprint ""
		(layer "B.Cu")
		(at 130.526282 -36.116006)
		(property "Reference" "R1206"
			(at 5.29463 3.511804 0)
			(unlocked yes)
			(layer "B.SilkS")
			(effects
				(font
					(size 0.7874 0.5842)
					(thickness 0.1524)
				)
				(justify left mirror)
			)
		)
		(property "Value" ""
			(at 0 0 0)
			(layer "B.Fab")
			(effects
				(font
					(size 1.27 1.27)
				)
				(justify mirror)
			)
		)
		(duplicate_pad_numbers_are_jumpers no)
		(fp_line
			(start -0.7874 -0.4064)
			(end -0.7874 0.4064)
			(stroke
				(width 0.1524)
				(type default)
			)
			(layer "B.SilkS")
		)
		(fp_line
			(start -0.7874 0.4064)
			(end 0.7874 0.4064)
			(stroke
				(width 0.1524)
				(type default)
			)
			(layer "B.SilkS")
		)
		(fp_line
			(start 0.7874 -0.4064)
			(end -0.7874 -0.4064)
			(stroke
				(width 0.1524)
				(type default)
			)
			(layer "B.SilkS")
		)
		(fp_line
			(start 0.7874 0.4064)
			(end 0.7874 -0.4064)
			(stroke
				(width 0.1524)
				(type default)
			)
			(layer "B.SilkS")
		)
		(fp_poly
			(pts
				(xy 0.508 0.2794) (xy 0.508 0.2286) (xy 0.635 0.2286) (xy 0.635 -0.254) (xy 0.5334 -0.254) (xy 0.5334 -0.2794)
				(xy -0.5334 -0.2794) (xy -0.5334 -0.254) (xy -0.635 -0.254) (xy -0.635 0.254) (xy -0.5334 0.254)
				(xy -0.5334 0.2794)
			)
			(stroke
				(width 0)
				(type default)
			)
			(fill no)
			(layer "B.CrtYd")
		)
		(pad "1" smd rect
			(at -0.40005 0 180)
			(size 0.4572 0.508)
			(layers "B.Cu" "B.Mask" "B.Paste")
			(net "SIO_JTAG_CPLD3_TDI")
		)
		(pad "2" smd rect
			(at 0.40005 0 180)
			(size 0.4572 0.508)
			(layers "B.Cu" "B.Mask" "B.Paste")
			(net "GND")
		)
	)
)
